# S9S_MB_2U (Grand Teton) — schematic netlist excerpt (pin names and nets, part order shuffled) for the footprints in the layout excerpt that follows; sources: Cadence DE-HDL packaged netlist, KiCad conversion of 03242023_DA0F0TMBIJ0_F0T_Motherboard_J_brd_V01_OCP.brd

C629  Q_CAP  0.1UF 25V 10% X7R  pkg 0402  page 243 : A = P3V3_AUX ; B = GND
R3097  Q_RES  130 1% CHIP  pkg 0402LF  page 254 : A = LED_PWRGD_PVNN_MAIN_CPU1 ; B = P3V3_AUX

(kicad_pcb
	(version 20260206)
	(generator "pcbnew")
	(generator_version "10.0")
	(general
		(thickness 1.6)
		(legacy_teardrops no)
	)
	(paper "A4")
	(title_block
		(title "03242023_DA0F0TMBIJ0_F0T_Motherboard_J_brd_V01_OCP.brd")
		(comment 1 "Grand Teton / footprints 549-550 of 6105")
	)
	(layers
		(0 "F.Cu" signal "TOP")
		(4 "In1.Cu" signal "GND")
		(6 "In2.Cu" signal "IN1")
		(8 "In3.Cu" signal "GND1")
		(10 "In4.Cu" signal "IN2")
		(12 "In5.Cu" signal "GND2")
		(14 "In6.Cu" signal "IN3")
		(16 "In7.Cu" signal "GND3")
		(18 "In8.Cu" signal "VCC")
		(20 "In9.Cu" signal "VCC1")
		(22 "In10.Cu" signal "GND4")
		(24 "In11.Cu" signal "IN4")
		(26 "In12.Cu" signal "GND5")
		(28 "In13.Cu" signal "IN5")
		(30 "In14.Cu" signal "GND6")
		(32 "In15.Cu" signal "IN6")
		(34 "In16.Cu" signal "GND7")
		(2 "B.Cu" signal "BOTTOM")
		(9 "F.Adhes" user "F.Adhesive")
		(11 "B.Adhes" user "B.Adhesive")
		(13 "F.Paste" user "Package Geometry/Pastemask Top")
		(15 "B.Paste" user "Package Geometry/Pastemask Bottom")
		(5 "F.SilkS" user "Ref Des/Silkscreen Top")
		(7 "B.SilkS" user "Ref Des/Silkscreen Bottom")
		(1 "F.Mask" user "Board Geometry/Soldermask Top")
		(3 "B.Mask" user "Board Geometry/Soldermask Bottom")
		(17 "Dwgs.User" user "User.Drawings")
		(19 "Cmts.User" user "User.Comments")
		(21 "Eco1.User" user "User.Eco1")
		(23 "Eco2.User" user "User.Eco2")
		(25 "Edge.Cuts" user "Board Geometry/Outline")
		(27 "Margin" user)
		(31 "F.CrtYd" user "Package Geometry/Place Bound Top")
		(29 "B.CrtYd" user "Package Geometry/Place Bound Bottom")
		(35 "F.Fab" user "Ref Des/Assembly Top")
		(33 "B.Fab" user "Ref Des/Assembly Bottom")
	)
	(footprint ""
		(layer "F.Cu")
		(at 289.27806 -95.760794)
		(property "Reference" "C629"
			(at 0 0 0)
			(layer "F.SilkS")
			(hide yes)
			(effects
				(font
					(size 1.27 1.27)
				)
			)
		)
		(property "Value" ""
			(at 0 0 0)
			(layer "F.Fab")
			(effects
				(font
					(size 1.27 1.27)
				)
			)
		)
		(duplicate_pad_numbers_are_jumpers no)
		(fp_line
			(start -0.7874 -0.4064)
			(end 0.7874 -0.4064)
			(stroke
				(width 0.1524)
				(type default)
			)
			(layer "F.SilkS")
		)
		(fp_line
			(start -0.7874 0.4064)
			(end -0.7874 -0.4064)
			(stroke
				(width 0.1524)
				(type default)
			)
			(layer "F.SilkS")
		)
		(fp_line
			(start 0.7874 -0.4064)
			(end 0.7874 0.4064)
			(stroke
				(width 0.1524)
				(type default)
			)
			(layer "F.SilkS")
		)
		(fp_line
			(start 0.7874 0.4064)
			(end -0.7874 0.4064)
			(stroke
				(width 0.1524)
				(type default)
			)
			(layer "F.SilkS")
		)
		(fp_line
			(start -0.67945 -0.305054)
			(end -0.12065 -0.305054)
			(stroke
				(width 0.1)
				(type default)
			)
			(layer "F.Fab")
		)
		(fp_line
			(start -0.67945 0.3048)
			(end -0.67945 -0.305054)
			(stroke
				(width 0.1)
				(type default)
			)
			(layer "F.Fab")
		)
		(fp_line
			(start -0.12065 -0.305054)
			(end -0.12065 -0.2794)
			(stroke
				(width 0.1)
				(type default)
			)
			(layer "F.Fab")
		)
		(fp_line
			(start -0.12065 -0.2794)
			(end 0.12065 -0.2794)
			(stroke
				(width 0.1)
				(type default)
			)
			(layer "F.Fab")
		)
		(fp_line
			(start -0.12065 0.2794)
			(end -0.12065 0.3048)
			(stroke
				(width 0.1)
				(type default)
			)
			(layer "F.Fab")
		)
		(fp_line
			(start -0.12065 0.3048)
			(end -0.67945 0.3048)
			(stroke
				(width 0.1)
				(type default)
			)
			(layer "F.Fab")
		)
		(fp_line
			(start 0.120396 0.2794)
			(end -0.12065 0.2794)
			(stroke
				(width 0.1)
				(type default)
			)
			(layer "F.Fab")
		)
		(fp_line
			(start 0.120396 0.3048)
			(end 0.120396 0.2794)
			(stroke
				(width 0.1)
				(type default)
			)
			(layer "F.Fab")
		)
		(fp_line
			(start 0.12065 -0.3048)
			(end 0.67945 -0.3048)
			(stroke
				(width 0.1)
				(type default)
			)
			(layer "F.Fab")
		)
		(fp_line
			(start 0.12065 -0.2794)
			(end 0.12065 -0.3048)
			(stroke
				(width 0.1)
				(type default)
			)
			(layer "F.Fab")
		)
		(fp_line
			(start 0.67945 -0.3048)
			(end 0.67945 0.3048)
			(stroke
				(width 0.1)
				(type default)
			)
			(layer "F.Fab")
		)
		(fp_line
			(start 0.67945 0.3048)
			(end 0.120396 0.3048)
			(stroke
				(width 0.1)
				(type default)
			)
			(layer "F.Fab")
		)
		(pad "1" smd circle
			(at -0.40005 0)
			(size 0 0)
			(layers "F.Cu" "F.Mask" "F.Paste")
			(net "P3V3_AUX")
		)
		(pad "2" smd circle
			(at 0.40005 0)
			(size 0 0)
			(layers "F.Cu" "F.Mask" "F.Paste")
			(net "GND")
		)
	)
	(footprint ""
		(layer "F.Cu")
		(at 102.86619 -65.12306 -90)
		(property "Reference" "R3097"
			(at 0 0 270)
			(layer "F.SilkS")
			(hide yes)
			(effects
				(font
					(size 1.27 1.27)
				)
			)
		)
		(property "Value" ""
			(at 0 0 270)
			(layer "F.Fab")
			(effects
				(font
					(size 1.27 1.27)
				)
			)
		)
		(duplicate_pad_numbers_are_jumpers no)
		(fp_line
			(start -0.7874 0.4064)
			(end -0.7874 -0.4064)
			(stroke
				(width 0.1524)
				(type default)
			)
			(layer "F.SilkS")
		)
		(fp_line
			(start 0.7874 0.4064)
			(end -0.7874 0.4064)
			(stroke
				(width 0.1524)
				(type default)
			)
			(layer "F.SilkS")
		)
		(fp_line
			(start -0.7874 -0.4064)
			(end 0.7874 -0.4064)
			(stroke
				(width 0.1524)
				(type default)
			)
			(layer "F.SilkS")
		)
		(fp_line
			(start 0.7874 -0.4064)
			(end 0.7874 0.4064)
			(stroke
				(width 0.1524)
				(type default)
			)
			(layer "F.SilkS")
		)
		(fp_line
			(start -0.67945 0.3048)
			(end -0.67945 -0.305054)
			(stroke
				(width 0.1)
				(type default)
			)
			(layer "F.Fab")
		)
		(fp_line
			(start -0.12065 0.3048)
			(end -0.67945 0.3048)
			(stroke
				(width 0.1)
				(type default)
			)
			(layer "F.Fab")
		)
		(fp_line
			(start 0.120396 0.3048)
			(end 0.120396 0.2794)
			(stroke
				(width 0.1)
				(type default)
			)
			(layer "F.Fab")
		)
		(fp_line
			(start 0.67945 0.3048)
			(end 0.120396 0.3048)
			(stroke
				(width 0.1)
				(type default)
			)
			(layer "F.Fab")
		)
		(fp_line
			(start -0.12065 0.2794)
			(end -0.12065 0.3048)
			(stroke
				(width 0.1)
				(type default)
			)
			(layer "F.Fab")
		)
		(fp_line
			(start 0.120396 0.2794)
			(end -0.12065 0.2794)
			(stroke
				(width 0.1)
				(type default)
			)
			(layer "F.Fab")
		)
		(fp_line
			(start -0.12065 -0.2794)
			(end 0.12065 -0.2794)
			(stroke
				(width 0.1)
				(type default)
			)
			(layer "F.Fab")
		)
		(fp_line
			(start 0.12065 -0.2794)
			(end 0.12065 -0.3048)
			(stroke
				(width 0.1)
				(type default)
			)
			(layer "F.Fab")
		)
		(fp_line
			(start 0.12065 -0.3048)
			(end 0.67945 -0.3048)
			(stroke
				(width 0.1)
				(type default)
			)
			(layer "F.Fab")
		)
		(fp_line
			(start 0.67945 -0.3048)
			(end 0.67945 0.3048)
			(stroke
				(width 0.1)
				(type default)
			)
			(layer "F.Fab")
		)
		(fp_line
			(start -0.67945 -0.305054)
			(end -0.12065 -0.305054)
			(stroke
				(width 0.1)
				(type default)
			)
			(layer "F.Fab")
		)
		(fp_line
			(start -0.12065 -0.305054)
			(end -0.12065 -0.2794)
			(stroke
				(width 0.1)
				(type default)
			)
			(layer "F.Fab")
		)
		(pad "1" smd circle
			(at -0.40005 0 270)
			(size 0 0)
			(layers "F.Cu" "F.Mask" "F.Paste")
			(net "LED_PWRGD_PVNN_MAIN_CPU1")
		)
		(pad "2" smd circle
			(at 0.40005 0 270)
			(size 0 0)
			(layers "F.Cu" "F.Mask" "F.Paste")
			(net "P3V3_AUX")
		)
	)
)
